# BASEBOARD_FAB2 (Tioga Pass) — schematic parts with pin connectivity, parts 2367–2368 of 4751; source: Cadence DE-HDL packaged netlist (pstxprt.dat, pstxnet.dat, pstchip.dat)

J4E1  SCONN120_H61426002  CONN  pkg SM  page 193
  A1  IOA1  BI  = PVCCMCP_CPU1
  A2  IOA2  BI  = PVCCMCP_CPU1
  A3  IOA3  BI  = PVCCMCP_CPU1
  A4  IOA4  BI  = VSENSE_PVCCMCP_CPU1_SKT_VSEN
  A5  IOA5  BI  = PVCCMCP_CPU1
  A6  IOA6  BI  = PVCCMCP_CPU1
  A7  IOA7  BI  = PVCCMCP_CPU1
  A8  IOA8  BI  = PVCCMCP_CPU1
  A9  IOA9  BI  = PVCCMCP_CPU1
  A10  IOA10  BI  = PVCCMCP_CPU1
  A11  IOA11  BI  = PVCCMCP_CPU1
  A12  IOA12  BI  = PVCCMCP_CPU1
  A13  IOA13  BI  = PVCCMCP_CPU1
  A14  IOA14  BI  = PVCCMCP_CPU1
  A15  IOA15  BI  = PVCCMCP_CPU1
  A16  IOA16  BI  = PVCCMCP_CPU1
  A17  IOA17  BI  = PVCCMCP_CPU1
  A18  IOA18  BI  = PVCCMCP_CPU1
  A19  IOA19  BI  = GND
  A20  IOA20  BI  = GND
  B1  IOB1  BI  = PVCCMCP_CPU1
  B2  IOB2  BI  = PVCCMCP_CPU1
  B3  IOB3  BI  = PVCCMCP_CPU1
  B4  IOB4  BI  = VSENSE_PVCCMCP_CPU1_SKT_VRTN
  B5  IOB5  BI  = PVCCMCP_CPU1
  B6  IOB6  BI  = PVCCMCP_CPU1
  B7  IOB7  BI  = PVCCMCP_CPU1
  B8  IOB8  BI  = PVCCMCP_CPU1
  B9  IOB9  BI  = PVCCMCP_CPU1
  B10  IOB10  BI  = PVCCMCP_CPU1
  B11  IOB11  BI  = PVCCMCP_CPU1
  B12  IOB12  BI  = PVCCMCP_CPU1
  B13  IOB13  BI  = PVCCMCP_CPU1
  B14  IOB14  BI  = PVCCMCP_CPU1
  B15  IOB15  BI  = PVCCMCP_CPU1
  B16  IOB16  BI  = PVCCMCP_CPU1
  B17  IOB17  BI  = PVCCMCP_CPU1
  B18  IOB18  BI  = PVCCMCP_CPU1
  B19  IOB19  BI  = GND
  B20  IOB20  BI  = GND
  C1  IOC1  BI  = PVCCMCP_CPU1
  C2  IOC2  BI  = PVCCMCP_CPU1
  C3  IOC3  BI  = PVCCMCP_CPU1
  C4  IOC4  BI  = PVCCMCP_CPU1
  C5  IOC5  BI  = PVCCMCP_CPU1
  C6  IOC6  BI  = PVCCMCP_CPU1
  C7  IOC7  BI  = PVCCMCP_CPU1
  C8  IOC8  BI  = PVCCMCP_CPU1
  C9  IOC9  BI  = PVCCMCP_CPU1
  C10  IOC10  BI  = PVCCMCP_CPU1
  C11  IOC11  BI  = PVCCMCP_CPU1
  C12  IOC12  BI  = PVCCMCP_CPU1
  C13  IOC13  BI  = PVCCMCP_CPU1
  C14  IOC14  BI  = PVCCMCP_CPU1
  C15  IOC15  BI  = PVCCMCP_CPU1
  C16  IOC16  BI  = PVCCMCP_CPU1
  C17  IOC17  BI  = PVCCMCP_CPU1
  C18  IOC18  BI  = PVCCMCP_CPU1
  C19  IOC19  BI  = GND
  C20  IOC20  BI  = GND
  D1  IOD1  BI  = VSENSE_P1V8MCP_CPU1_SKT_VSEN
  D2  IOD2  BI  = VSENSE_P1V8MCP_CPU1_SKT_VRTN
  D3  IOD3  BI  = P1V8_MCP_CPU1
  D4  IOD4  BI  = GND
  D5  IOD5  BI  = GND
  D6  IOD6  BI  = GND
  D7  IOD7  BI  = GND
  D8  IOD8  BI  = GND
  D9  IOD9  BI  = GND
  D10  IOD10  BI  = GND
  D11  IOD11  BI  = GND
  D12  IOD12  BI  = GND
  D13  IOD13  BI  = GND
  D14  IOD14  BI  = GND
  D15  IOD15  BI  = GND
  D16  IOD16  BI  = GND
  D17  IOD17  BI  = GND
  D18  IOD18  BI  = GND
  D19  IOD19  BI  = GND
  D20  IOD20  BI  = GND
  E1  IOE1  BI  = P1V8_MCP_CPU1
  E2  IOE2  BI  = P1V8_MCP_CPU1
  E3  IOE3  BI  = P1V8_MCP_CPU1
  E4  IOE4  BI  = GND
  E5  IOE5  BI  = CLK_322M_156M_CPU1_OSC_VRM_DP
  E6  IOE6  BI  = GND
  E7  IOE7  BI  = GND
  E8  IOE8  BI  = GND
  E9  IOE9  BI  = GND
  E10  IOE10  BI  = GND
  E11  IOE11  BI  = GND
  E12  IOE12  BI  = GND
  E13  IOE13  BI  = GND
  E14  IOE14  BI  = GND
  E15  IOE15  BI  = GND
  E16  IOE16  BI  = GND
  E17  IOE17  BI  = GND
  E18  IOE18  BI  = GND
  E19  IOE19  BI  = GND
  E20  IOE20  BI  = GND
  F1  IOF1  BI  = P1V8_MCP_CPU1
  F2  IOF2  BI  = P1V8_MCP_CPU1
  F3  IOF3  BI  = P1V8_MCP_CPU1
  F4  IOF4  BI  = GND
  F5  IOF5  BI  = CLK_322M_156M_CPU1_OSC_VRM_DN
  F6  IOF6  BI  = GND
  F7  IOF7  BI  = GND
  F8  IOF8  BI  = GND
  F9  IOF9  BI  = GND
  F10  IOF10  BI  = GND
  F11  IOF11  BI  = GND
  F12  IOF12  BI  = GND
  F13  IOF13  BI  = GND
  F14  IOF14  BI  = GND
  F15  IOF15  BI  = GND
  F16  IOF16  BI  = GND
  F17  IOF17  BI  = GND
  F18  IOF18  BI  = GND
  F19  IOF19  BI  = GND
  F20  IOF20  BI  = GND

J4G1  SCONN288_H44441004  SCONN  pkg PIP  page 43
  1  \12v\(1)  = P12V_NVDIMM_ABC
  2  VSS(93)  GROUND  = GND
  3  DQ(4)  BI  = M_A_DQ<5>
  4  VSS(92)  GROUND  = GND
  5  DQ(0)  BI  = M_A_DQ<1>
  6  VSS(91)  GROUND  = GND
  7  DQS9P  BI  = M_A_DQS_DP<9>
  8  DQS9N  BI  = M_A_DQS_DN<9>
  9  VSS(90)  GROUND  = GND
  10  DQ(6)  BI  = M_A_DQ<7>
  11  VSS(89)  GROUND  = GND
  12  DQ(2)  BI  = M_A_DQ<3>
  13  VSS(88)  GROUND  = GND
  14  DQ(12)  BI  = M_A_DQ<13>
  15  VSS(87)  GROUND  = GND
  16  DQ(8)  BI  = M_A_DQ<9>
  17  VSS(86)  GROUND  = GND
  18  DQS10P  BI  = M_A_DQS_DP<10>
  19  DQS10N  BI  = M_A_DQS_DN<10>
  20  VSS(85)  GROUND  = GND
  21  DQ(14)  BI  = M_A_DQ<15>
  22  VSS(84)  GROUND  = GND
  23  DQ(10)  BI  = M_A_DQ<11>
  24  VSS(83)  GROUND  = GND
  25  DQ(20)  BI  = M_A_DQ<21>
  26  VSS(82)  GROUND  = GND
  27  DQ(16)  BI  = M_A_DQ<17>
  28  VSS(81)  GROUND  = GND
  29  DQS11P  BI  = M_A_DQS_DP<11>
  30  DQS11N  BI  = M_A_DQS_DN<11>
  31  VSS(80)  GROUND  = GND
  32  DQ(22)  BI  = M_A_DQ<23>
  33  VSS(79)  GROUND  = GND
  34  DQ(18)  BI  = M_A_DQ<19>
  35  VSS(78)  GROUND  = GND
  36  DQ(28)  BI  = M_A_DQ<29>
  37  VSS(77)  GROUND  = GND
  38  DQ(24)  BI  = M_A_DQ<25>
  39  VSS(76)  GROUND  = GND
  40  DQS12P  BI  = M_A_DQS_DP<12>
  41  DQS12N  BI  = M_A_DQS_DN<12>
  42  VSS(75)  GROUND  = GND
  43  DQ(30)  BI  = M_A_DQ<31>
  44  VSS(74)  GROUND  = GND
  45  DQ(26)  BI  = M_A_DQ<27>
  46  VSS(73)  GROUND  = GND
  47  CB(4)  BI  = M_A_ECC<5>
  48  VSS(72)  GROUND  = GND
  49  CB(0)  BI  = M_A_ECC<1>
  50  VSS(71)  GROUND  = GND
  51  DQS17P  BI  = M_A_DQS_DP<17>
  52  DQS17N  BI  = M_A_DQS_DN<17>
  53  VSS(70)  GROUND  = GND
  54  CB(6)  BI  = M_A_ECC<7>
  55  VSS(69)  GROUND  = GND
  56  CB(2)  BI  = M_A_ECC<3>
  57  VSS(68)  GROUND  = GND
  58  RESET_N  BI  = M_ABC_RST_N
  59  VDD(25)  POWER  = PVDDQ_ABC
  60  CKE(0)  BI  = M_A_CKE<0>
  61  VDD(24)  POWER  = PVDDQ_ABC
  62  ACT_N  BI  = M_A_ACT_N
  63  BG(0)  BI  = M_A_BG<0>
  64  VDD(23)  POWER  = PVDDQ_ABC
  65  A12  BI  = M_A_MA<12>
  66  A9  BI  = M_A_MA<9>
  67  VDD(22)  POWER  = PVDDQ_ABC
  68  A8  BI  = M_A_MA<8>
  69  A6  BI  = M_A_MA<6>
  70  VDD(21)  POWER  = PVDDQ_ABC
  71  A3  BI  = M_A_MA<3>
  72  A1  BI  = M_A_MA<1>
  73  VDD(20)  POWER  = PVDDQ_ABC
  74  CK0P  BI  = M_A_CLK_DP<0>
  75  CK0N  BI  = M_A_CLK_DN<0>
  76  VDD(19)  POWER  = PVDDQ_ABC
  77  VTT(1)  POWER  = PVTT_ABC
  78  EVENT_N  BI  = FM_DIMM_EVENT_COD_N
  79  A0  BI  = M_A_MA<0>
  80  VDD(18)  POWER  = PVDDQ_ABC
  81  BA(0)  BI  = M_A_BA<0>
  82  A16_RAS_N  BI  = M_A_MA<16>
  83  VDD(17)  POWER  = PVDDQ_ABC
  84  S0_N  BI  = M_A_CS_N<0>
  85  VDD(16)  POWER  = PVDDQ_ABC
  86  A15_CAS_N  BI  = M_A_MA<15>
  87  ODT(0)  BI  = M_A_ODT<0>
  88  VDD(15)  POWER  = PVDDQ_ABC
  89  S1_N  BI  = M_A_CS_N<1>
  90  VDD(14)  POWER  = PVDDQ_ABC
  91  ODT(1)  BI  = M_A_ODT<1>
  92  VDD(13)  POWER  = PVDDQ_ABC
  93  S2_N_C(0)  BI  = M_A_CS_N<2>
  94  VSS(67)  GROUND  = GND
  95  DQ(36)  BI  = M_A_DQ<37>
  96  VSS(66)  GROUND  = GND
  97  DQ(32)  BI  = M_A_DQ<33>
  98  VSS(65)  GROUND  = GND
  99  DQS13P  BI  = M_A_DQS_DP<13>
  100  DQS13N  BI  = M_A_DQS_DN<13>
  101  VSS(64)  GROUND  = GND
  102  DQ(38)  BI  = M_A_DQ<39>
  103  VSS(63)  GROUND  = GND
  104  DQ(34)  BI  = M_A_DQ<35>
  105  VSS(62)  GROUND  = GND
  106  DQ(44)  BI  = M_A_DQ<45>
  107  VSS(61)  GROUND  = GND
  108  DQ(40)  BI  = M_A_DQ<41>
  109  VSS(60)  GROUND  = GND
  110  DQS14P  BI  = M_A_DQS_DP<14>
  111  DQS14N  BI  = M_A_DQS_DN<14>
  112  VSS(59)  GROUND  = GND
  113  DQ(46)  BI  = M_A_DQ<47>
  114  VSS(58)  GROUND  = GND
  115  DQ(42)  BI  = M_A_DQ<43>
  116  VSS(57)  GROUND  = GND
  117  DQ(52)  BI  = M_A_DQ<53>
  118  VSS(56)  GROUND  = GND
  119  DQ(48)  BI  = M_A_DQ<49>
  120  VSS(55)  GROUND  = GND
  121  DQS15P  BI  = M_A_DQS_DP<15>
  122  DQS15N  BI  = M_A_DQS_DN<15>
  123  VSS(54)  GROUND  = GND
  124  DQ(54)  BI  = M_A_DQ<55>
  125  VSS(53)  GROUND  = GND
  126  DQ(50)  BI  = M_A_DQ<51>
  127  VSS(52)  GROUND  = GND
  128  DQ(60)  BI  = M_A_DQ<61>
  129  VSS(51)  GROUND  = GND
  130  DQ(56)  BI  = M_A_DQ<57>
  131  VSS(50)  GROUND  = GND
  132  DQS16P  BI  = M_A_DQS_DP<16>
  133  DQS16N  BI  = M_A_DQS_DN<16>
  134  VSS(49)  GROUND  = GND
  135  DQ(62)  BI  = M_A_DQ<63>
  136  VSS(48)  GROUND  = GND
  137  DQ(58)  BI  = M_A_DQ<59>
  138  VSS(47)  GROUND  = GND
  139  SA(0)  BI  = GND
  140  SA(1)  BI  = GND
  141  SCL  BI  = SMB_DDR_ABC_VPP_SCL
  142  VPP(4)  POWER  = PVPP_ABC
  143  VPP(3)  POWER  = PVPP_ABC
  144  RFU(2)  BI  = TP_CH_A_DIMM_A0_RFU_2
  145  \12v\(0)  = P12V_NVDIMM_ABC
  146  VREFCA  BI  = M_A_VREF
  147  VSS(46)  GROUND  = GND
  148  DQ(5)  BI  = M_A_DQ<4>
  149  VSS(45)  GROUND  = GND
  150  DQ(1)  BI  = M_A_DQ<0>
  151  VSS(44)  GROUND  = GND
  152  DQS0N  BI  = M_A_DQS_DN<0>
  153  DQS0P  BI  = M_A_DQS_DP<0>
  154  VSS(43)  GROUND  = GND
  155  DQ(7)  BI  = M_A_DQ<6>
  156  VSS(42)  GROUND  = GND
  157  DQ(3)  BI  = M_A_DQ<2>
  158  VSS(41)  GROUND  = GND
  159  DQ(13)  BI  = M_A_DQ<12>
  160  VSS(40)  GROUND  = GND
  161  DQ(9)  BI  = M_A_DQ<8>
  162  VSS(39)  GROUND  = GND
  163  DQS1N  BI  = M_A_DQS_DN<1>
  164  DQS1P  BI  = M_A_DQS_DP<1>
  165  VSS(38)  GROUND  = GND
  166  DQ(15)  BI  = M_A_DQ<14>
  167  VSS(37)  GROUND  = GND
  168  DQ(11)  BI  = M_A_DQ<10>
  169  VSS(36)  GROUND  = GND
  170  DQ(21)  BI  = M_A_DQ<20>
  171  VSS(35)  GROUND  = GND
  172  DQ(17)  BI  = M_A_DQ<16>
  173  VSS(34)  GROUND  = GND
  174  DQS2N  BI  = M_A_DQS_DN<2>
  175  DQS2P  BI  = M_A_DQS_DP<2>
  176  VSS(33)  GROUND  = GND
  177  DQ(23)  BI  = M_A_DQ<22>
  178  VSS(32)  GROUND  = GND
  179  DQ(19)  BI  = M_A_DQ<18>
  180  VSS(31)  GROUND  = GND
  181  DQ(29)  BI  = M_A_DQ<28>
  182  VSS(30)  GROUND  = GND
  183  DQ(25)  BI  = M_A_DQ<24>
  184  VSS(29)  GROUND  = GND
  185  DQS3N  BI  = M_A_DQS_DN<3>
  186  DQS3P  BI  = M_A_DQS_DP<3>
  187  VSS(28)  GROUND  = GND
  188  DQ(31)  BI  = M_A_DQ<30>
  189  VSS(27)  GROUND  = GND
  190  DQ(27)  BI  = M_A_DQ<26>
  191  VSS(26)  GROUND  = GND
  192  CB(5)  BI  = M_A_ECC<4>
  193  VSS(25)  GROUND  = GND
  194  CB(1)  BI  = M_A_ECC<0>
  195  VSS(24)  GROUND  = GND
  196  DQS8N  BI  = M_A_DQS_DN<8>
  197  DQS8P  BI  = M_A_DQS_DP<8>
  198  VSS(23)  GROUND  = GND
  199  CB(7)  BI  = M_A_ECC<6>
  200  VSS(22)  GROUND  = GND
  201  CB(3)  BI  = M_A_ECC<2>
  202  VSS(21)  GROUND  = GND
  203  CKE(1)  BI  = M_A_CKE<1>
  204  VDD(12)  POWER  = PVDDQ_ABC
  205  RFU(0)  BI  = TP_CH_A_DIMM_A0_RFU_0
  206  VDD(11)  POWER  = PVDDQ_ABC
  207  BG(1)  BI  = M_A_BG<1>
  208  ALERT_N  BI  = M_A_ALERT_N
  209  VDD(10)  POWER  = PVDDQ_ABC
  210  A11  BI  = M_A_MA<11>
  211  A7  BI  = M_A_MA<7>
  212  VDD(9)  POWER  = PVDDQ_ABC
  213  A5  BI  = M_A_MA<5>
  214  A4  BI  = M_A_MA<4>
  215  VDD(8)  POWER  = PVDDQ_ABC
  216  A2  BI  = M_A_MA<2>
  217  VDD(7)  POWER  = PVDDQ_ABC
  218  CK1P  BI  = M_A_CLK_DP<1>
  219  CK1N  BI  = M_A_CLK_DN<1>
  220  VDD(6)  POWER  = PVDDQ_ABC
  221  VTT(0)  POWER  = PVTT_ABC
  222  PAR  BI  = M_A_PAR
  223  VDD(5)  POWER  = PVDDQ_ABC
  224  BA(1)  BI  = M_A_BA<1>
  225  A10  BI  = M_A_MA<10>
  226  VDD(4)  POWER  = PVDDQ_ABC
  227  RFU(1)  BI  = TP_CH_A_DIMM_A0_RFU_1
  228  A14_WE_N  BI  = M_A_MA<14>
  229  VDD(3)  POWER  = PVDDQ_ABC
  230  SAVE_N_NC  BI  = FM_ADR_COMPLETE_ABC_N
  231  VDD(2)  POWER  = PVDDQ_ABC
  232  A13  BI  = M_A_MA<13>
  233  VDD(1)  POWER  = PVDDQ_ABC
  234  A17  BI  = M_A_MA<17>
  235  C(2)  BI  = M_A_C<2>
  236  VDD(0)  POWER  = PVDDQ_ABC
  237  S3_N_C(1)  BI  = M_A_CS_N<3>
  238  SA(2)  BI  = GND
  239  VSS(20)  GROUND  = GND
  240  DQ(37)  BI  = M_A_DQ<36>
  241  VSS(19)  GROUND  = GND
  242  DQ(33)  BI  = M_A_DQ<32>
  243  VSS(18)  GROUND  = GND
  244  DQS4N  BI  = M_A_DQS_DN<4>
  245  DQS4P  BI  = M_A_DQS_DP<4>
  246  VSS(17)  GROUND  = GND
  247  DQ(39)  BI  = M_A_DQ<38>
  248  VSS(16)  GROUND  = GND
  249  DQ(35)  BI  = M_A_DQ<34>
  250  VSS(15)  GROUND  = GND
  251  DQ(45)  BI  = M_A_DQ<44>
  252  VSS(14)  GROUND  = GND
  253  DQ(41)  BI  = M_A_DQ<40>
  254  VSS(13)  GROUND  = GND
  255  DQS5N  BI  = M_A_DQS_DN<5>
  256  DQS5P  BI  = M_A_DQS_DP<5>
  257  VSS(12)  GROUND  = GND
  258  DQ(47)  BI  = M_A_DQ<46>
  259  VSS(11)  GROUND  = GND
  260  DQ(43)  BI  = M_A_DQ<42>
  261  VSS(10)  GROUND  = GND
  262  DQ(53)  BI  = M_A_DQ<52>
  263  VSS(9)  GROUND  = GND
  264  DQ(49)  BI  = M_A_DQ<48>
  265  VSS(8)  GROUND  = GND
  266  DQS6N  BI  = M_A_DQS_DN<6>
  267  DQS6P  BI  = M_A_DQS_DP<6>
  268  VSS(7)  GROUND  = GND
  269  DQ(55)  BI  = M_A_DQ<54>
  270  VSS(6)  GROUND  = GND
  271  DQ(51)  BI  = M_A_DQ<50>
  272  VSS(5)  GROUND  = GND
  273  DQ(61)  BI  = M_A_DQ<60>
  274  VSS(4)  GROUND  = GND
  275  DQ(57)  BI  = M_A_DQ<56>
  276  VSS(3)  GROUND  = GND
  277  DQS7N  BI  = M_A_DQS_DN<7>
  278  DQS7P  BI  = M_A_DQS_DP<7>
  279  VSS(2)  GROUND  = GND
  280  DQ(63)  BI  = M_A_DQ<62>
  281  VSS(1)  GROUND  = GND
  282  DQ(59)  BI  = M_A_DQ<58>
  283  VSS(0)  GROUND  = GND
  284  VDDSPD  BI  = PVPP_ABC
  285  SDA  BI  = SMB_DDR_ABC_VPP_SDA
  286  VPP(1)  POWER  = PVPP_ABC
  287  VPP(0)  POWER  = PVPP_ABC
  288  VPP(2)  POWER  = PVPP_ABC
